# T6G (Grand Teton) — schematic netlist excerpt (pin names and nets, part order shuffled) for the footprints in the layout excerpt that follows; sources: Cadence DE-HDL packaged netlist, KiCad conversion of 04192023_DAF0TMB3IC0_F0TG_MB_C_brd_V02_OCP.brd

PR52  Q_RES  49.9 1% CHIP  pkg 0402LF  page 200 : A = VSENSE_PVDDIO_P0_DP ; B = PVDDIO_P0
R487  Q_RES  0 5% CHIP  pkg 0402LF  page 188 : A = SW_P3V3_EN ; B = SW_P3V3_EN_R

(kicad_pcb
	(version 20260206)
	(generator "pcbnew")
	(generator_version "10.0")
	(general
		(thickness 1.6)
		(legacy_teardrops no)
	)
	(paper "A4")
	(title_block
		(title "04192023_DAF0TMB3IC0_F0TG_MB_C_brd_V02_OCP.brd")
		(comment 1 "Grand Teton / footprints 4020-4021 of 8354")
	)
	(layers
		(0 "F.Cu" signal "TOP")
		(4 "In1.Cu" signal "GND")
		(6 "In2.Cu" signal "IN1")
		(8 "In3.Cu" signal "GND1")
		(10 "In4.Cu" signal "IN2")
		(12 "In5.Cu" signal "GND2")
		(14 "In6.Cu" signal "IN3")
		(16 "In7.Cu" signal "GND3")
		(18 "In8.Cu" signal "VCC")
		(20 "In9.Cu" signal "VCC1")
		(22 "In10.Cu" signal "GND4")
		(24 "In11.Cu" signal "IN4")
		(26 "In12.Cu" signal "GND5")
		(28 "In13.Cu" signal "IN5")
		(30 "In14.Cu" signal "GND6")
		(32 "In15.Cu" signal "IN6")
		(34 "In16.Cu" signal "GND7")
		(2 "B.Cu" signal "BOTTOM")
		(9 "F.Adhes" user "F.Adhesive")
		(11 "B.Adhes" user "B.Adhesive")
		(13 "F.Paste" user "Package Geometry/Pastemask Top")
		(15 "B.Paste" user "Package Geometry/Pastemask Bottom")
		(5 "F.SilkS" user "Ref Des/Silkscreen Top")
		(7 "B.SilkS" user "Ref Des/Silkscreen Bottom")
		(1 "F.Mask" user "Board Geometry/Soldermask Top")
		(3 "B.Mask" user "Board Geometry/Soldermask Bottom")
		(17 "Dwgs.User" user "User.Drawings")
		(19 "Cmts.User" user "User.Comments")
		(21 "Eco1.User" user "User.Eco1")
		(23 "Eco2.User" user "User.Eco2")
		(25 "Edge.Cuts" user "Board Geometry/Outline")
		(27 "Margin" user)
		(31 "F.CrtYd" user "Package Geometry/Place Bound Top")
		(29 "B.CrtYd" user "Package Geometry/Place Bound Bottom")
		(35 "F.Fab" user "Ref Des/Assembly Top")
		(33 "B.Fab" user "Ref Des/Assembly Bottom")
	)
	(footprint ""
		(layer "F.Cu")
		(at 205.232 -130.048)
		(property "Reference" "R487"
			(at 0 0 0)
			(layer "F.SilkS")
			(hide yes)
			(effects
				(font
					(size 1.27 1.27)
				)
			)
		)
		(property "Value" ""
			(at 0 0 0)
			(layer "F.Fab")
			(effects
				(font
					(size 1.27 1.27)
				)
			)
		)
		(duplicate_pad_numbers_are_jumpers no)
		(fp_line
			(start -0.7874 -0.4064)
			(end 0.7874 -0.4064)
			(stroke
				(width 0.1524)
				(type default)
			)
			(layer "F.SilkS")
		)
		(fp_line
			(start -0.7874 0.4064)
			(end -0.7874 -0.4064)
			(stroke
				(width 0.1524)
				(type default)
			)
			(layer "F.SilkS")
		)
		(fp_line
			(start 0.7874 -0.4064)
			(end 0.7874 0.4064)
			(stroke
				(width 0.1524)
				(type default)
			)
			(layer "F.SilkS")
		)
		(fp_line
			(start 0.7874 0.4064)
			(end -0.7874 0.4064)
			(stroke
				(width 0.1524)
				(type default)
			)
			(layer "F.SilkS")
		)
		(fp_line
			(start -0.67945 -0.305054)
			(end -0.12065 -0.305054)
			(stroke
				(width 0.1)
				(type default)
			)
			(layer "F.Fab")
		)
		(fp_line
			(start -0.67945 0.3048)
			(end -0.67945 -0.305054)
			(stroke
				(width 0.1)
				(type default)
			)
			(layer "F.Fab")
		)
		(fp_line
			(start -0.12065 -0.305054)
			(end -0.12065 -0.2794)
			(stroke
				(width 0.1)
				(type default)
			)
			(layer "F.Fab")
		)
		(fp_line
			(start -0.12065 -0.2794)
			(end 0.12065 -0.2794)
			(stroke
				(width 0.1)
				(type default)
			)
			(layer "F.Fab")
		)
		(fp_line
			(start -0.12065 0.2794)
			(end -0.12065 0.3048)
			(stroke
				(width 0.1)
				(type default)
			)
			(layer "F.Fab")
		)
		(fp_line
			(start -0.12065 0.3048)
			(end -0.67945 0.3048)
			(stroke
				(width 0.1)
				(type default)
			)
			(layer "F.Fab")
		)
		(fp_line
			(start 0.120396 0.2794)
			(end -0.12065 0.2794)
			(stroke
				(width 0.1)
				(type default)
			)
			(layer "F.Fab")
		)
		(fp_line
			(start 0.120396 0.3048)
			(end 0.120396 0.2794)
			(stroke
				(width 0.1)
				(type default)
			)
			(layer "F.Fab")
		)
		(fp_line
			(start 0.12065 -0.3048)
			(end 0.67945 -0.3048)
			(stroke
				(width 0.1)
				(type default)
			)
			(layer "F.Fab")
		)
		(fp_line
			(start 0.12065 -0.2794)
			(end 0.12065 -0.3048)
			(stroke
				(width 0.1)
				(type default)
			)
			(layer "F.Fab")
		)
		(fp_line
			(start 0.67945 -0.3048)
			(end 0.67945 0.3048)
			(stroke
				(width 0.1)
				(type default)
			)
			(layer "F.Fab")
		)
		(fp_line
			(start 0.67945 0.3048)
			(end 0.120396 0.3048)
			(stroke
				(width 0.1)
				(type default)
			)
			(layer "F.Fab")
		)
		(pad "1" smd circle
			(at -0.40005 0)
			(size 0 0)
			(layers "F.Cu" "F.Mask" "F.Paste")
			(net "SW_P3V3_EN")
		)
		(pad "2" smd circle
			(at 0.40005 0)
			(size 0 0)
			(layers "F.Cu" "F.Mask" "F.Paste")
			(net "SW_P3V3_EN_R")
		)
	)
	(footprint ""
		(layer "F.Cu")
		(at 269.023084 -332.029562)
		(property "Reference" "PR52"
			(at 0 0 0)
			(layer "F.SilkS")
			(hide yes)
			(effects
				(font
					(size 1.27 1.27)
				)
			)
		)
		(property "Value" ""
			(at 0 0 0)
			(layer "F.Fab")
			(effects
				(font
					(size 1.27 1.27)
				)
			)
		)
		(duplicate_pad_numbers_are_jumpers no)
		(fp_line
			(start -0.7874 -0.4064)
			(end 0.7874 -0.4064)
			(stroke
				(width 0.1524)
				(type default)
			)
			(layer "F.SilkS")
		)
		(fp_line
			(start -0.7874 0.4064)
			(end -0.7874 -0.4064)
			(stroke
				(width 0.1524)
				(type default)
			)
			(layer "F.SilkS")
		)
		(fp_line
			(start 0.7874 -0.4064)
			(end 0.7874 0.4064)
			(stroke
				(width 0.1524)
				(type default)
			)
			(layer "F.SilkS")
		)
		(fp_line
			(start 0.7874 0.4064)
			(end -0.7874 0.4064)
			(stroke
				(width 0.1524)
				(type default)
			)
			(layer "F.SilkS")
		)
		(fp_line
			(start -0.67945 -0.305054)
			(end -0.12065 -0.305054)
			(stroke
				(width 0.1)
				(type default)
			)
			(layer "F.Fab")
		)
		(fp_line
			(start -0.67945 0.3048)
			(end -0.67945 -0.305054)
			(stroke
				(width 0.1)
				(type default)
			)
			(layer "F.Fab")
		)
		(fp_line
			(start -0.12065 -0.305054)
			(end -0.12065 -0.2794)
			(stroke
				(width 0.1)
				(type default)
			)
			(layer "F.Fab")
		)
		(fp_line
			(start -0.12065 -0.2794)
			(end 0.12065 -0.2794)
			(stroke
				(width 0.1)
				(type default)
			)
			(layer "F.Fab")
		)
		(fp_line
			(start -0.12065 0.2794)
			(end -0.12065 0.3048)
			(stroke
				(width 0.1)
				(type default)
			)
			(layer "F.Fab")
		)
		(fp_line
			(start -0.12065 0.3048)
			(end -0.67945 0.3048)
			(stroke
				(width 0.1)
				(type default)
			)
			(layer "F.Fab")
		)
		(fp_line
			(start 0.120396 0.2794)
			(end -0.12065 0.2794)
			(stroke
				(width 0.1)
				(type default)
			)
			(layer "F.Fab")
		)
		(fp_line
			(start 0.120396 0.3048)
			(end 0.120396 0.2794)
			(stroke
				(width 0.1)
				(type default)
			)
			(layer "F.Fab")
		)
		(fp_line
			(start 0.12065 -0.3048)
			(end 0.67945 -0.3048)
			(stroke
				(width 0.1)
				(type default)
			)
			(layer "F.Fab")
		)
		(fp_line
			(start 0.12065 -0.2794)
			(end 0.12065 -0.3048)
			(stroke
				(width 0.1)
				(type default)
			)
			(layer "F.Fab")
		)
		(fp_line
			(start 0.67945 -0.3048)
			(end 0.67945 0.3048)
			(stroke
				(width 0.1)
				(type default)
			)
			(layer "F.Fab")
		)
		(fp_line
			(start 0.67945 0.3048)
			(end 0.120396 0.3048)
			(stroke
				(width 0.1)
				(type default)
			)
			(layer "F.Fab")
		)
		(pad "1" smd circle
			(at -0.40005 0)
			(size 0 0)
			(layers "F.Cu" "F.Mask" "F.Paste")
			(net "VSENSE_PVDDIO_P0_DP")
		)
		(pad "2" smd circle
			(at 0.40005 0)
			(size 0 0)
			(layers "F.Cu" "F.Mask" "F.Paste")
			(net "PVDDIO_P0")
		)
	)
)
